(kicad_pcb
	(version 20260206)
	(generator "pcbnew")
	(generator_version "10.0")
	(general
		(thickness 1.6)
		(legacy_teardrops no)
	)
	(paper "A4")
	(title_block
		(title "panther-plus-userver — 13130-1b_20150205.brd")
		(comment 1 "Honey Badger (Wiwynn) / footprints 807-815 of 1509")
	)
	(layers
		(0 "F.Cu" signal "TOP")
		(4 "In1.Cu" signal "L2")
		(6 "In2.Cu" signal "L3")
		(8 "In3.Cu" signal "L4")
		(10 "In4.Cu" signal "L5")
		(12 "In5.Cu" signal "L6")
		(14 "In6.Cu" signal "L7")
		(16 "In7.Cu" signal "L8")
		(18 "In8.Cu" signal "L9")
		(20 "In9.Cu" signal "L10")
		(22 "In10.Cu" signal "L11")
		(2 "B.Cu" signal "BOTTOM")
		(9 "F.Adhes" user "F.Adhesive")
		(11 "B.Adhes" user "B.Adhesive")
		(13 "F.Paste" user "Package Geometry/Pastemask Top")
		(15 "B.Paste" user "Package Geometry/Pastemask Bottom")
		(5 "F.SilkS" user "Ref Des/Silkscreen Top")
		(7 "B.SilkS" user "Ref Des/Silkscreen Bottom")
		(1 "F.Mask" user "Board Geometry/Soldermask Top")
		(3 "B.Mask" user "Board Geometry/Soldermask Bottom")
		(17 "Dwgs.User" user "User.Drawings")
		(19 "Cmts.User" user "User.Comments")
		(21 "Eco1.User" user "User.Eco1")
		(23 "Eco2.User" user "User.Eco2")
		(25 "Edge.Cuts" user "Board Geometry/Outline")
		(27 "Margin" user)
		(31 "F.CrtYd" user "Package Geometry/Place Bound Top")
		(29 "B.CrtYd" user "Package Geometry/Place Bound Bottom")
		(35 "F.Fab" user "Ref Des/Assembly Top")
		(33 "B.Fab" user "Ref Des/Assembly Bottom")
	)
	(footprint ""
		(layer "F.Cu")
		(at 137.541 -18.415 -90)
		(property "Reference" "R470"
			(at 0 0 270)
			(layer "F.SilkS")
			(hide yes)
			(effects
				(font
					(size 1.27 1.27)
				)
			)
		)
		(property "Value" "4K7R2F-GP"
			(at 1.7907 -1.1176 270)
			(unlocked yes)
			(layer "F.Fab")
			(hide yes)
			(effects
				(font
					(size 1.016 1.016)
					(thickness 0.1524)
				)
			)
		)
		(property "Device Type" "R402H16"
			(at 1.7907 -2.6416 270)
			(unlocked yes)
			(layer "F.Fab")
			(hide yes)
			(effects
				(font
					(size 1.016 1.016)
					(thickness 0.1524)
				)
			)
		)
		(duplicate_pad_numbers_are_jumpers no)
		(fp_rect
			(start -0.381 0.8382)
			(end 0.381 -0.8382)
			(stroke
				(width 0)
				(type default)
			)
			(fill no)
			(layer "F.CrtYd")
		)
		(fp_rect
			(start -0.381 0.8382)
			(end 0.381 -0.8382)
			(stroke
				(width 0)
				(type default)
			)
			(fill no)
			(layer "F.Fab")
		)
		(pad "1" smd custom
			(at 0 -0.4318 270)
			(size 0.127 0.127)
			(layers "F.Cu" "F.Mask" "F.Paste")
			(net "P3V3_STBY")
			(options
				(clearance outline)
				(anchor circle)
			)
			(primitives
				(gr_poly
					(pts
						(arc
							(start -0.2032 -0.2794)
							(mid -0.239121 -0.264521)
							(end -0.254 -0.2286)
						)
						(arc
							(start -0.254 0.2286)
							(mid -0.239121 0.264521)
							(end -0.2032 0.2794)
						)
						(arc
							(start 0.2032 0.2794)
							(mid 0.239121 0.264521)
							(end 0.254 0.2286)
						)
						(arc
							(start 0.254 -0.2286)
							(mid 0.239121 -0.264521)
							(end 0.2032 -0.2794)
						)
					)
					(width 0)
					(fill yes)
				)
			)
		)
		(pad "2" smd custom
			(at 0 0.4318 270)
			(size 0.127 0.127)
			(layers "F.Cu" "F.Mask" "F.Paste")
			(net "HOST_LV_D_RSTBTN#")
			(options
				(clearance outline)
				(anchor circle)
			)
			(primitives
				(gr_poly
					(pts
						(arc
							(start -0.2032 -0.2794)
							(mid -0.239121 -0.264521)
							(end -0.254 -0.2286)
						)
						(arc
							(start -0.254 0.2286)
							(mid -0.239121 0.264521)
							(end -0.2032 0.2794)
						)
						(arc
							(start 0.2032 0.2794)
							(mid 0.239121 0.264521)
							(end 0.254 0.2286)
						)
						(arc
							(start 0.254 -0.2286)
							(mid 0.239121 -0.264521)
							(end 0.2032 -0.2794)
						)
					)
					(width 0)
					(fill yes)
				)
			)
		)
	)
	(footprint ""
		(layer "F.Cu")
		(at 109.1438 -19.177 90)
		(property "Reference" "R167"
			(at 0 0 90)
			(layer "F.SilkS")
			(hide yes)
			(effects
				(font
					(size 1.27 1.27)
				)
			)
		)
		(property "Value" "100R3F-1-GP"
			(at -0.0254 -2.5146 90)
			(unlocked yes)
			(layer "F.Fab")
			(hide yes)
			(effects
				(font
					(size 1.016 1.016)
					(thickness 0.1524)
				)
			)
		)
		(property "Device Type" "R603H22"
			(at -0.0254 -4.0386 90)
			(unlocked yes)
			(layer "F.Fab")
			(hide yes)
			(effects
				(font
					(size 1.016 1.016)
					(thickness 0.1524)
				)
			)
		)
		(duplicate_pad_numbers_are_jumpers no)
		(fp_line
			(start 0.4318 0)
			(end 0.2032 0)
			(stroke
				(width 0.2032)
				(type default)
			)
			(layer "F.SilkS")
		)
		(fp_line
			(start -0.2032 0)
			(end -0.4191 0)
			(stroke
				(width 0.2032)
				(type default)
			)
			(layer "F.SilkS")
		)
		(fp_rect
			(start -0.635 1.1811)
			(end 0.635 -1.1811)
			(stroke
				(width 0)
				(type default)
			)
			(fill no)
			(layer "F.CrtYd")
		)
		(fp_rect
			(start -0.635 1.1811)
			(end 0.635 -1.1811)
			(stroke
				(width 0)
				(type default)
			)
			(fill no)
			(layer "F.Fab")
		)
		(pad "1" smd custom
			(at 0 -0.6604 90)
			(size 0.19685 0.19685)
			(layers "F.Cu" "F.Mask" "F.Paste")
			(net "M_B_MON2_P")
			(options
				(clearance outline)
				(anchor circle)
			)
			(primitives
				(gr_poly
					(pts
						(arc
							(start 0.508 -0.2921)
							(mid 0.478242 -0.363942)
							(end 0.4064 -0.3937)
						)
						(arc
							(start -0.4064 -0.3937)
							(mid -0.478242 -0.363942)
							(end -0.508 -0.2921)
						)
						(arc
							(start -0.508 0.2921)
							(mid -0.478242 0.363942)
							(end -0.4064 0.3937)
						)
						(arc
							(start 0.4064 0.3937)
							(mid 0.478242 0.363942)
							(end 0.508 0.2921)
						)
					)
					(width 0)
					(fill yes)
				)
			)
		)
		(pad "2" smd custom
			(at 0 0.6604 90)
			(size 0.19685 0.19685)
			(layers "F.Cu" "F.Mask" "F.Paste")
			(net "M_B_MON2_N")
			(options
				(clearance outline)
				(anchor circle)
			)
			(primitives
				(gr_poly
					(pts
						(arc
							(start 0.508 -0.2921)
							(mid 0.478242 -0.363942)
							(end 0.4064 -0.3937)
						)
						(arc
							(start -0.4064 -0.3937)
							(mid -0.478242 -0.363942)
							(end -0.508 -0.2921)
						)
						(arc
							(start -0.508 0.2921)
							(mid -0.478242 0.363942)
							(end -0.4064 0.3937)
						)
						(arc
							(start 0.4064 0.3937)
							(mid 0.478242 0.363942)
							(end 0.508 0.2921)
						)
					)
					(width 0)
					(fill yes)
				)
			)
		)
	)
	(footprint ""
		(layer "F.Cu")
		(at 16.0528 -51.2572 90)
		(property "Reference" "PC147"
			(at 0 0 90)
			(layer "F.SilkS")
			(hide yes)
			(effects
				(font
					(size 1.27 1.27)
				)
			)
		)
		(property "Value" "SC100P50V2JN-3GP"
			(at 1.8923 -1.2065 90)
			(unlocked yes)
			(layer "F.Fab")
			(hide yes)
			(effects
				(font
					(size 1.016 1.016)
					(thickness 0.1524)
				)
			)
		)
		(property "Device Type" "C402H22"
			(at 1.8923 -2.7305 90)
			(unlocked yes)
			(layer "F.Fab")
			(hide yes)
			(effects
				(font
					(size 1.016 1.016)
					(thickness 0.1524)
				)
			)
		)
		(duplicate_pad_numbers_are_jumpers no)
		(fp_rect
			(start -0.381 0.7366)
			(end 0.381 -0.7366)
			(stroke
				(width 0)
				(type default)
			)
			(fill no)
			(layer "F.CrtYd")
		)
		(fp_rect
			(start -0.381 0.7366)
			(end 0.381 -0.7366)
			(stroke
				(width 0)
				(type default)
			)
			(fill no)
			(layer "F.Fab")
		)
		(pad "1" smd custom
			(at 0 -0.4572 90)
			(size 0.1143 0.1143)
			(layers "F.Cu" "F.Mask" "F.Paste")
			(net "VR_PVCCP_COMP")
			(options
				(clearance outline)
				(anchor circle)
			)
			(primitives
				(gr_poly
					(pts
						(arc
							(start -0.254 -0.1778)
							(mid -0.239121 -0.213721)
							(end -0.2032 -0.2286)
						)
						(arc
							(start 0.2032 -0.2286)
							(mid 0.239121 -0.213721)
							(end 0.254 -0.1778)
						)
						(arc
							(start 0.254 0.1778)
							(mid 0.239121 0.213721)
							(end 0.2032 0.2286)
						)
						(arc
							(start -0.2032 0.2286)
							(mid -0.239121 0.213721)
							(end -0.254 0.1778)
						)
					)
					(width 0)
					(fill yes)
				)
			)
		)
		(pad "2" smd custom
			(at 0 0.4572 90)
			(size 0.1143 0.1143)
			(layers "F.Cu" "F.Mask" "F.Paste")
			(net "VR_PVCCP_FB")
			(options
				(clearance outline)
				(anchor circle)
			)
			(primitives
				(gr_poly
					(pts
						(arc
							(start -0.254 -0.1778)
							(mid -0.239121 -0.213721)
							(end -0.2032 -0.2286)
						)
						(arc
							(start 0.2032 -0.2286)
							(mid 0.239121 -0.213721)
							(end 0.254 -0.1778)
						)
						(arc
							(start 0.254 0.1778)
							(mid 0.239121 0.213721)
							(end 0.2032 0.2286)
						)
						(arc
							(start -0.2032 0.2286)
							(mid -0.239121 0.213721)
							(end -0.254 0.1778)
						)
					)
					(width 0)
					(fill yes)
				)
			)
		)
	)
	(footprint ""
		(layer "F.Cu")
		(at 5.08 -25.527)
		(property "Reference" "PC91"
			(at 0 0 0)
			(layer "F.SilkS")
			(hide yes)
			(effects
				(font
					(size 1.27 1.27)
				)
			)
		)
		(property "Value" "SC22U25V5MX-GP"
			(at 0 -4.9022 0)
			(unlocked yes)
			(layer "F.Fab")
			(hide yes)
			(effects
				(font
					(size 1.016 1.016)
					(thickness 0.1524)
				)
			)
		)
		(property "Device Type" "C805H58"
			(at 0 -6.8072 0)
			(unlocked yes)
			(layer "F.Fab")
			(hide yes)
			(effects
				(font
					(size 1.016 1.016)
					(thickness 0.1524)
				)
			)
		)
		(duplicate_pad_numbers_are_jumpers no)
		(fp_line
			(start 0.6096 0)
			(end -0.6096 0)
			(stroke
				(width 0.3048)
				(type default)
			)
			(layer "F.SilkS")
		)
		(fp_poly
			(pts
				(xy -0.9017 1.4351) (xy 0.9017 1.4351) (xy 0.9017 -1.4351) (xy -0.9017 -1.4351)
			)
			(stroke
				(width 0)
				(type default)
			)
			(fill no)
			(layer "F.CrtYd")
		)
		(fp_poly
			(pts
				(xy 0.9017 1.4351) (xy 0.9017 -1.4351) (xy -0.9017 -1.4351) (xy -0.9017 1.4351)
			)
			(stroke
				(width 0)
				(type default)
			)
			(fill no)
			(layer "F.Fab")
		)
		(pad "1" smd rect
			(at 0 -0.8382)
			(size 1.5494 0.9398)
			(layers "F.Cu" "F.Mask" "F.Paste")
			(net "P1V0_VIN")
		)
		(pad "2" smd rect
			(at 0 0.8382)
			(size 1.5494 0.9398)
			(layers "F.Cu" "F.Mask" "F.Paste")
			(net "GND")
		)
	)
	(footprint ""
		(layer "F.Cu")
		(at 28.829 -13.335)
		(property "Reference" "R462"
			(at 0 0 0)
			(layer "F.SilkS")
			(hide yes)
			(effects
				(font
					(size 1.27 1.27)
				)
			)
		)
		(property "Value" "4K7R2F-GP"
			(at 1.7907 -1.1176 0)
			(unlocked yes)
			(layer "F.Fab")
			(hide yes)
			(effects
				(font
					(size 1.016 1.016)
					(thickness 0.1524)
				)
			)
		)
		(property "Device Type" "R402H16"
			(at 1.7907 -2.6416 0)
			(unlocked yes)
			(layer "F.Fab")
			(hide yes)
			(effects
				(font
					(size 1.016 1.016)
					(thickness 0.1524)
				)
			)
		)
		(duplicate_pad_numbers_are_jumpers no)
		(fp_rect
			(start -0.381 0.8382)
			(end 0.381 -0.8382)
			(stroke
				(width 0)
				(type default)
			)
			(fill no)
			(layer "F.CrtYd")
		)
		(fp_rect
			(start -0.381 0.8382)
			(end 0.381 -0.8382)
			(stroke
				(width 0)
				(type default)
			)
			(fill no)
			(layer "F.Fab")
		)
		(pad "1" smd custom
			(at 0 -0.4318)
			(size 0.127 0.127)
			(layers "F.Cu" "F.Mask" "F.Paste")
			(net "P3V3_STBY")
			(options
				(clearance outline)
				(anchor circle)
			)
			(primitives
				(gr_poly
					(pts
						(arc
							(start -0.2032 -0.2794)
							(mid -0.239121 -0.264521)
							(end -0.254 -0.2286)
						)
						(arc
							(start -0.254 0.2286)
							(mid -0.239121 0.264521)
							(end -0.2032 0.2794)
						)
						(arc
							(start 0.2032 0.2794)
							(mid 0.239121 0.264521)
							(end 0.254 0.2286)
						)
						(arc
							(start 0.254 -0.2286)
							(mid 0.239121 -0.264521)
							(end 0.2032 -0.2794)
						)
					)
					(width 0)
					(fill yes)
				)
			)
		)
		(pad "2" smd custom
			(at 0 0.4318)
			(size 0.127 0.127)
			(layers "F.Cu" "F.Mask" "F.Paste")
			(net "PCIE_GF_I2C_CLK")
			(options
				(clearance outline)
				(anchor circle)
			)
			(primitives
				(gr_poly
					(pts
						(arc
							(start -0.2032 -0.2794)
							(mid -0.239121 -0.264521)
							(end -0.254 -0.2286)
						)
						(arc
							(start -0.254 0.2286)
							(mid -0.239121 0.264521)
							(end -0.2032 0.2794)
						)
						(arc
							(start 0.2032 0.2794)
							(mid 0.239121 0.264521)
							(end 0.254 0.2286)
						)
						(arc
							(start 0.254 -0.2286)
							(mid 0.239121 -0.264521)
							(end 0.2032 -0.2794)
						)
					)
					(width 0)
					(fill yes)
				)
			)
		)
	)
	(footprint ""
		(layer "F.Cu")
		(at 204.7748 -27.686 90)
		(property "Reference" "TP17"
			(at 0 0 90)
			(layer "F.SilkS")
			(hide yes)
			(effects
				(font
					(size 1.27 1.27)
				)
			)
		)
		(property "Value" "TPAD32-GP"
			(at 0 -3.166364 90)
			(unlocked yes)
			(layer "F.Fab")
			(hide yes)
			(effects
				(font
					(size 1.016 1.016)
					(thickness 0.1524)
				)
			)
		)
		(property "Device Type" "TPAD32"
			(at 0 -4.690618 90)
			(unlocked yes)
			(layer "F.Fab")
			(hide yes)
			(effects
				(font
					(size 1.016 1.016)
					(thickness 0.1524)
				)
			)
		)
		(duplicate_pad_numbers_are_jumpers no)
		(fp_poly
			(pts
				(arc
					(start 0 0.7112)
					(mid 0 -0.7112)
					(end 0 0.7112)
				)
			)
			(stroke
				(width 0)
				(type default)
			)
			(fill no)
			(layer "F.CrtYd")
		)
		(fp_poly
			(pts
				(arc
					(start 0 0.7112)
					(mid 0 -0.7112)
					(end 0 0.7112)
				)
			)
			(stroke
				(width 0)
				(type default)
			)
			(fill no)
			(layer "F.Fab")
		)
		(pad "1" smd circle
			(at 0 0 90)
			(size 0.8128 0.8128)
			(layers "F.Cu" "F.Mask" "F.Paste")
			(net "JTAG_PLD_TDI")
		)
	)
	(footprint ""
		(layer "B.Cu")
		(at 138.303 -24.384 90)
		(property "Reference" "C165"
			(at 0 0 90)
			(layer "B.SilkS")
			(hide yes)
			(effects
				(font
					(size 1.27 1.27)
				)
				(justify mirror)
			)
		)
		(property "Value" "SCD1U10V2KX-5GP"
			(at -1.1811 -2.7051 90)
			(unlocked yes)
			(layer "B.Fab")
			(hide yes)
			(effects
				(font
					(size 1.016 1.016)
					(thickness 0.1524)
				)
				(justify mirror)
			)
		)
		(property "Device Type" "C402H22"
			(at -1.1811 -4.2291 90)
			(unlocked yes)
			(layer "B.Fab")
			(hide yes)
			(effects
				(font
					(size 1.016 1.016)
					(thickness 0.1524)
				)
				(justify mirror)
			)
		)
		(duplicate_pad_numbers_are_jumpers no)
		(fp_rect
			(start 0.381 0.7366)
			(end -0.381 -0.7366)
			(stroke
				(width 0)
				(type default)
			)
			(fill no)
			(layer "B.CrtYd")
		)
		(fp_rect
			(start 0.381 0.7366)
			(end -0.381 -0.7366)
			(stroke
				(width 0)
				(type default)
			)
			(fill no)
			(layer "B.Fab")
		)
		(pad "1" smd custom
			(at 0 -0.4572 270)
			(size 0.1143 0.1143)
			(layers "B.Cu" "B.Mask" "B.Paste")
			(net "P3V3_STBY")
			(options
				(clearance outline)
				(anchor circle)
			)
			(primitives
				(gr_poly
					(pts
						(arc
							(start -0.254 0.1778)
							(mid -0.239121 0.213721)
							(end -0.2032 0.2286)
						)
						(arc
							(start 0.2032 0.2286)
							(mid 0.239121 0.213721)
							(end 0.254 0.1778)
						)
						(arc
							(start 0.254 -0.1778)
							(mid 0.239121 -0.213721)
							(end 0.2032 -0.2286)
						)
						(arc
							(start -0.2032 -0.2286)
							(mid -0.239121 -0.213721)
							(end -0.254 -0.1778)
						)
					)
					(width 0)
					(fill yes)
				)
			)
		)
		(pad "2" smd custom
			(at 0 0.4572 270)
			(size 0.1143 0.1143)
			(layers "B.Cu" "B.Mask" "B.Paste")
			(net "GND")
			(options
				(clearance outline)
				(anchor circle)
			)
			(primitives
				(gr_poly
					(pts
						(arc
							(start -0.254 0.1778)
							(mid -0.239121 0.213721)
							(end -0.2032 0.2286)
						)
						(arc
							(start 0.2032 0.2286)
							(mid 0.239121 0.213721)
							(end 0.254 0.1778)
						)
						(arc
							(start 0.254 -0.1778)
							(mid 0.239121 -0.213721)
							(end 0.2032 -0.2286)
						)
						(arc
							(start -0.2032 -0.2286)
							(mid -0.239121 -0.213721)
							(end -0.254 -0.1778)
						)
					)
					(width 0)
					(fill yes)
				)
			)
		)
	)
	(footprint ""
		(layer "B.Cu")
		(at 101.727 -51.451002 180)
		(property "Reference" "C130"
			(at 0 0 0)
			(layer "B.SilkS")
			(hide yes)
			(effects
				(font
					(size 1.27 1.27)
				)
				(justify mirror)
			)
		)
		(property "Value" "SC1U10V2KX-1GP"
			(at -1.1811 -2.7051 180)
			(unlocked yes)
			(layer "B.Fab")
			(hide yes)
			(effects
				(font
					(size 1.016 1.016)
					(thickness 0.1524)
				)
				(justify mirror)
			)
		)
		(property "Device Type" "C402H22"
			(at -1.1811 -4.2291 180)
			(unlocked yes)
			(layer "B.Fab")
			(hide yes)
			(effects
				(font
					(size 1.016 1.016)
					(thickness 0.1524)
				)
				(justify mirror)
			)
		)
		(duplicate_pad_numbers_are_jumpers no)
		(fp_rect
			(start 0.381 0.7366)
			(end -0.381 -0.7366)
			(stroke
				(width 0)
				(type default)
			)
			(fill no)
			(layer "B.CrtYd")
		)
		(fp_rect
			(start 0.381 0.7366)
			(end -0.381 -0.7366)
			(stroke
				(width 0)
				(type default)
			)
			(fill no)
			(layer "B.Fab")
		)
		(pad "1" smd custom
			(at 0 -0.4572)
			(size 0.1143 0.1143)
			(layers "B.Cu" "B.Mask" "B.Paste")
			(net "PV_VDDR")
			(options
				(clearance outline)
				(anchor circle)
			)
			(primitives
				(gr_poly
					(pts
						(arc
							(start -0.254 0.1778)
							(mid -0.239121 0.213721)
							(end -0.2032 0.2286)
						)
						(arc
							(start 0.2032 0.2286)
							(mid 0.239121 0.213721)
							(end 0.254 0.1778)
						)
						(arc
							(start 0.254 -0.1778)
							(mid 0.239121 -0.213721)
							(end 0.2032 -0.2286)
						)
						(arc
							(start -0.2032 -0.2286)
							(mid -0.239121 -0.213721)
							(end -0.254 -0.1778)
						)
					)
					(width 0)
					(fill yes)
				)
			)
		)
		(pad "2" smd custom
			(at 0 0.4572)
			(size 0.1143 0.1143)
			(layers "B.Cu" "B.Mask" "B.Paste")
			(net "GND")
			(options
				(clearance outline)
				(anchor circle)
			)
			(primitives
				(gr_poly
					(pts
						(arc
							(start -0.254 0.1778)
							(mid -0.239121 0.213721)
							(end -0.2032 0.2286)
						)
						(arc
							(start 0.2032 0.2286)
							(mid 0.239121 0.213721)
							(end 0.254 0.1778)
						)
						(arc
							(start 0.254 -0.1778)
							(mid 0.239121 -0.213721)
							(end 0.2032 -0.2286)
						)
						(arc
							(start -0.2032 -0.2286)
							(mid -0.239121 -0.213721)
							(end -0.254 -0.1778)
						)
					)
					(width 0)
					(fill yes)
				)
			)
		)
	)
	(footprint ""
		(layer "B.Cu")
		(at 144.399 -23.495 90)
		(property "Reference" "C197"
			(at 0 0 90)
			(layer "B.SilkS")
			(hide yes)
			(effects
				(font
					(size 1.27 1.27)
				)
				(justify mirror)
			)
		)
		(property "Value" "SCD1U10V2KX-5GP"
			(at -1.1811 -2.7051 90)
			(unlocked yes)
			(layer "B.Fab")
			(hide yes)
			(effects
				(font
					(size 1.016 1.016)
					(thickness 0.1524)
				)
				(justify mirror)
			)
		)
		(property "Device Type" "C402H22"
			(at -1.1811 -4.2291 90)
			(unlocked yes)
			(layer "B.Fab")
			(hide yes)
			(effects
				(font
					(size 1.016 1.016)
					(thickness 0.1524)
				)
				(justify mirror)
			)
		)
		(duplicate_pad_numbers_are_jumpers no)
		(fp_rect
			(start 0.381 0.7366)
			(end -0.381 -0.7366)
			(stroke
				(width 0)
				(type default)
			)
			(fill no)
			(layer "B.CrtYd")
		)
		(fp_rect
			(start 0.381 0.7366)
			(end -0.381 -0.7366)
			(stroke
				(width 0)
				(type default)
			)
			(fill no)
			(layer "B.Fab")
		)
		(pad "1" smd custom
			(at 0 -0.4572 270)
			(size 0.1143 0.1143)
			(layers "B.Cu" "B.Mask" "B.Paste")
			(net "P3V3_STBY")
			(options
				(clearance outline)
				(anchor circle)
			)
			(primitives
				(gr_poly
					(pts
						(arc
							(start -0.254 0.1778)
							(mid -0.239121 0.213721)
							(end -0.2032 0.2286)
						)
						(arc
							(start 0.2032 0.2286)
							(mid 0.239121 0.213721)
							(end 0.254 0.1778)
						)
						(arc
							(start 0.254 -0.1778)
							(mid 0.239121 -0.213721)
							(end 0.2032 -0.2286)
						)
						(arc
							(start -0.2032 -0.2286)
							(mid -0.239121 -0.213721)
							(end -0.254 -0.1778)
						)
					)
					(width 0)
					(fill yes)
				)
			)
		)
		(pad "2" smd custom
			(at 0 0.4572 270)
			(size 0.1143 0.1143)
			(layers "B.Cu" "B.Mask" "B.Paste")
			(net "GND")
			(options
				(clearance outline)
				(anchor circle)
			)
			(primitives
				(gr_poly
					(pts
						(arc
							(start -0.254 0.1778)
							(mid -0.239121 0.213721)
							(end -0.2032 0.2286)
						)
						(arc
							(start 0.2032 0.2286)
							(mid 0.239121 0.213721)
							(end 0.254 0.1778)
						)
						(arc
							(start 0.254 -0.1778)
							(mid 0.239121 -0.213721)
							(end 0.2032 -0.2286)
						)
						(arc
							(start -0.2032 -0.2286)
							(mid -0.239121 -0.213721)
							(end -0.254 -0.1778)
						)
					)
					(width 0)
					(fill yes)
				)
			)
		)
	)
)
